(kicad_pcb
	(version 20260206)
	(generator "pcbnew")
	(generator_version "10.0")
	(general
		(thickness 1.6)
		(legacy_teardrops no)
	)
	(paper "A4")
	(title_block
		(title "baseboard — 13948-1b.1110WZS1818.brd")
		(comment 1 "Honey Badger (Wiwynn) / footprints 1961-1968 of 2523")
	)
	(layers
		(0 "F.Cu" signal "TOP")
		(4 "In1.Cu" signal "L2GND")
		(6 "In2.Cu" signal "L3")
		(8 "In3.Cu" signal "L4VCC")
		(10 "In4.Cu" signal "L5VCC")
		(12 "In5.Cu" signal "L6")
		(14 "In6.Cu" signal "L7GND")
		(2 "B.Cu" signal "BOTTOM")
		(9 "F.Adhes" user "F.Adhesive")
		(11 "B.Adhes" user "B.Adhesive")
		(13 "F.Paste" user "Package Geometry/Pastemask Top")
		(15 "B.Paste" user "Package Geometry/Pastemask Bottom")
		(5 "F.SilkS" user "Ref Des/Silkscreen Top")
		(7 "B.SilkS" user "Ref Des/Silkscreen Bottom")
		(1 "F.Mask" user "Board Geometry/Soldermask Top")
		(3 "B.Mask" user "Board Geometry/Soldermask Bottom")
		(17 "Dwgs.User" user "User.Drawings")
		(19 "Cmts.User" user "User.Comments")
		(21 "Eco1.User" user "User.Eco1")
		(23 "Eco2.User" user "User.Eco2")
		(25 "Edge.Cuts" user "Board Geometry/Outline")
		(27 "Margin" user)
		(31 "F.CrtYd" user "Package Geometry/Place Bound Top")
		(29 "B.CrtYd" user "Package Geometry/Place Bound Bottom")
		(35 "F.Fab" user "Ref Des/Assembly Top")
		(33 "B.Fab" user "Ref Des/Assembly Bottom")
	)
	(footprint ""
		(layer "B.Cu")
		(at 99.549966 -40.64)
		(property "Reference" "SC1018"
			(at 0 0 0)
			(layer "B.SilkS")
			(hide yes)
			(effects
				(font
					(size 1.27 1.27)
				)
				(justify mirror)
			)
		)
		(property "Value" "SC10U6D3V5KX-4GP"
			(at 0.0762 -6.1214 0)
			(unlocked yes)
			(layer "B.Fab")
			(hide yes)
			(effects
				(font
					(size 1.016 1.016)
					(thickness 0.1524)
				)
				(justify mirror)
			)
		)
		(property "Device Type" "C805H58"
			(at 0.0762 -8.1534 0)
			(unlocked yes)
			(layer "B.Fab")
			(hide yes)
			(effects
				(font
					(size 1.016 1.016)
					(thickness 0.1524)
				)
				(justify mirror)
			)
		)
		(duplicate_pad_numbers_are_jumpers no)
		(fp_line
			(start -0.635 0)
			(end 0.635 0)
			(stroke
				(width 0.508)
				(type default)
			)
			(layer "B.SilkS")
		)
		(fp_rect
			(start 0.9652 1.778)
			(end -0.9652 -1.778)
			(stroke
				(width 0)
				(type default)
			)
			(fill no)
			(layer "B.CrtYd")
		)
		(fp_poly
			(pts
				(xy 0.9652 -1.778) (xy -0.9652 -1.778) (xy -0.9652 1.778) (xy 0.9652 1.778)
			)
			(stroke
				(width 0)
				(type default)
			)
			(fill no)
			(layer "B.Fab")
		)
		(pad "1" smd rect
			(at 0 -0.9652 180)
			(size 1.397 1.143)
			(layers "B.Cu" "B.Mask" "B.Paste")
			(net "P0V955_C")
		)
		(pad "2" smd rect
			(at 0 0.9652 180)
			(size 1.397 1.143)
			(layers "B.Cu" "B.Mask" "B.Paste")
			(net "GND")
		)
	)
	(footprint ""
		(layer "B.Cu")
		(at 274.193 -172.593 90)
		(property "Reference" "R241"
			(at 0 0 90)
			(layer "B.SilkS")
			(hide yes)
			(effects
				(font
					(size 1.27 1.27)
				)
				(justify mirror)
			)
		)
		(property "Value" "0R2J-2-GP"
			(at -0.064008 -3.993896 90)
			(unlocked yes)
			(layer "B.Fab")
			(hide yes)
			(effects
				(font
					(size 1.016 1.016)
					(thickness 0.1524)
				)
				(justify mirror)
			)
		)
		(property "Device Type" "R402H16"
			(at -0.064008 -5.517896 90)
			(unlocked yes)
			(layer "B.Fab")
			(hide yes)
			(effects
				(font
					(size 1.016 1.016)
					(thickness 0.1524)
				)
				(justify mirror)
			)
		)
		(duplicate_pad_numbers_are_jumpers no)
		(fp_line
			(start 0.508 -0.9398)
			(end 0.508 0.9398)
			(stroke
				(width 0.1524)
				(type default)
			)
			(layer "B.SilkS")
		)
		(fp_line
			(start -0.508 -0.9398)
			(end 0.508 -0.9398)
			(stroke
				(width 0.1524)
				(type default)
			)
			(layer "B.SilkS")
		)
		(fp_rect
			(start 0.508 0.9398)
			(end -0.508 -0.9398)
			(stroke
				(width 0)
				(type default)
			)
			(fill no)
			(layer "B.CrtYd")
		)
		(fp_rect
			(start 0.508 0.9398)
			(end -0.508 -0.9398)
			(stroke
				(width 0)
				(type default)
			)
			(fill no)
			(layer "B.Fab")
		)
		(pad "1" smd custom
			(at 0 -0.4445 270)
			(size 0.1397 0.1397)
			(layers "B.Cu" "B.Mask" "B.Paste")
			(net "BMC_10G_SDA_2")
			(options
				(clearance outline)
				(anchor circle)
			)
			(primitives
				(gr_poly
					(pts
						(arc
							(start -0.1778 0.2794)
							(mid -0.249642 0.249642)
							(end -0.2794 0.1778)
						)
						(arc
							(start -0.2794 -0.1778)
							(mid -0.249642 -0.249642)
							(end -0.1778 -0.2794)
						)
						(arc
							(start 0.1778 -0.2794)
							(mid 0.249642 -0.249642)
							(end 0.2794 -0.1778)
						)
						(arc
							(start 0.2794 0.1778)
							(mid 0.249642 0.249642)
							(end 0.1778 0.2794)
						)
					)
					(width 0)
					(fill yes)
				)
			)
		)
		(pad "2" smd custom
			(at 0 0.4445 270)
			(size 0.1397 0.1397)
			(layers "B.Cu" "B.Mask" "B.Paste")
			(net "BMC0_SMB2_DAT")
			(options
				(clearance outline)
				(anchor circle)
			)
			(primitives
				(gr_poly
					(pts
						(arc
							(start -0.1778 0.2794)
							(mid -0.249642 0.249642)
							(end -0.2794 0.1778)
						)
						(arc
							(start -0.2794 -0.1778)
							(mid -0.249642 -0.249642)
							(end -0.1778 -0.2794)
						)
						(arc
							(start 0.1778 -0.2794)
							(mid 0.249642 -0.249642)
							(end 0.2794 -0.1778)
						)
						(arc
							(start 0.2794 0.1778)
							(mid 0.249642 0.249642)
							(end 0.1778 0.2794)
						)
					)
					(width 0)
					(fill yes)
				)
			)
		)
	)
	(footprint ""
		(layer "B.Cu")
		(at 158.877 -89.154)
		(property "Reference" "PC179"
			(at 0 0 0)
			(layer "B.SilkS")
			(hide yes)
			(effects
				(font
					(size 1.27 1.27)
				)
				(justify mirror)
			)
		)
		(property "Value" "SC22U6D3V3MX-1-GP"
			(at 0 -2.8194 0)
			(unlocked yes)
			(layer "B.Fab")
			(hide yes)
			(effects
				(font
					(size 1.016 1.016)
					(thickness 0.1524)
				)
				(justify mirror)
			)
		)
		(property "Device Type" "C603H40"
			(at 0 -4.3434 0)
			(unlocked yes)
			(layer "B.Fab")
			(hide yes)
			(effects
				(font
					(size 1.016 1.016)
					(thickness 0.1524)
				)
				(justify mirror)
			)
		)
		(duplicate_pad_numbers_are_jumpers no)
		(fp_line
			(start -0.508 0)
			(end 0.508 0)
			(stroke
				(width 0.2032)
				(type default)
			)
			(layer "B.SilkS")
		)
		(fp_rect
			(start 0.5842 1.3335)
			(end -0.5842 -1.3335)
			(stroke
				(width 0)
				(type default)
			)
			(fill no)
			(layer "B.CrtYd")
		)
		(fp_rect
			(start 0.5842 1.3335)
			(end -0.5842 -1.3335)
			(stroke
				(width 0)
				(type default)
			)
			(fill no)
			(layer "B.Fab")
		)
		(pad "1" smd custom
			(at 0 -0.762 180)
			(size 0.2159 0.2159)
			(layers "B.Cu" "B.Mask" "B.Paste")
			(net "P0V9_E")
			(options
				(clearance outline)
				(anchor circle)
			)
			(primitives
				(gr_poly
					(pts
						(arc
							(start -0.3302 0.4318)
							(mid -0.402042 0.402042)
							(end -0.4318 0.3302)
						)
						(arc
							(start -0.4318 -0.3302)
							(mid -0.402042 -0.402042)
							(end -0.3302 -0.4318)
						)
						(arc
							(start 0.3302 -0.4318)
							(mid 0.402042 -0.402042)
							(end 0.4318 -0.3302)
						)
						(arc
							(start 0.4318 0.3302)
							(mid 0.402042 0.402042)
							(end 0.3302 0.4318)
						)
					)
					(width 0)
					(fill yes)
				)
			)
		)
		(pad "2" smd custom
			(at 0 0.762 180)
			(size 0.2159 0.2159)
			(layers "B.Cu" "B.Mask" "B.Paste")
			(net "GND")
			(options
				(clearance outline)
				(anchor circle)
			)
			(primitives
				(gr_poly
					(pts
						(arc
							(start -0.3302 0.4318)
							(mid -0.402042 0.402042)
							(end -0.4318 0.3302)
						)
						(arc
							(start -0.4318 -0.3302)
							(mid -0.402042 -0.402042)
							(end -0.3302 -0.4318)
						)
						(arc
							(start 0.3302 -0.4318)
							(mid 0.402042 -0.402042)
							(end 0.4318 -0.3302)
						)
						(arc
							(start 0.4318 0.3302)
							(mid 0.402042 0.402042)
							(end 0.3302 0.4318)
						)
					)
					(width 0)
					(fill yes)
				)
			)
		)
	)
	(footprint ""
		(layer "B.Cu")
		(at 107.2388 -40.3352)
		(property "Reference" "SC1049"
			(at 0 0 0)
			(layer "B.SilkS")
			(hide yes)
			(effects
				(font
					(size 1.27 1.27)
				)
				(justify mirror)
			)
		)
		(property "Value" "SCD1U16V2KX-3GP"
			(at -1.1811 -2.7051 0)
			(unlocked yes)
			(layer "B.Fab")
			(hide yes)
			(effects
				(font
					(size 1.016 1.016)
					(thickness 0.1524)
				)
				(justify mirror)
			)
		)
		(property "Device Type" "C402H22"
			(at -1.1811 -4.2291 0)
			(unlocked yes)
			(layer "B.Fab")
			(hide yes)
			(effects
				(font
					(size 1.016 1.016)
					(thickness 0.1524)
				)
				(justify mirror)
			)
		)
		(duplicate_pad_numbers_are_jumpers no)
		(fp_rect
			(start 0.4318 0.9525)
			(end -0.4318 -0.9525)
			(stroke
				(width 0)
				(type default)
			)
			(fill no)
			(layer "B.CrtYd")
		)
		(fp_rect
			(start 0.4318 0.9525)
			(end -0.4318 -0.9525)
			(stroke
				(width 0)
				(type default)
			)
			(fill no)
			(layer "B.Fab")
		)
		(pad "1" smd custom
			(at 0 -0.4445 180)
			(size 0.1524 0.1524)
			(layers "B.Cu" "B.Mask" "B.Paste")
			(net "P0V955_C")
			(options
				(clearance outline)
				(anchor circle)
			)
			(primitives
				(gr_poly
					(pts
						(arc
							(start 0.3048 0.2032)
							(mid 0.275042 0.275042)
							(end 0.2032 0.3048)
						)
						(arc
							(start -0.2032 0.3048)
							(mid -0.275042 0.275042)
							(end -0.3048 0.2032)
						)
						(arc
							(start -0.3048 -0.2032)
							(mid -0.275042 -0.275042)
							(end -0.2032 -0.3048)
						)
						(arc
							(start 0.2032 -0.3048)
							(mid 0.275042 -0.275042)
							(end 0.3048 -0.2032)
						)
					)
					(width 0)
					(fill yes)
				)
			)
		)
		(pad "2" smd custom
			(at 0 0.4445 180)
			(size 0.1524 0.1524)
			(layers "B.Cu" "B.Mask" "B.Paste")
			(net "GND")
			(options
				(clearance outline)
				(anchor circle)
			)
			(primitives
				(gr_poly
					(pts
						(arc
							(start 0.3048 0.2032)
							(mid 0.275042 0.275042)
							(end 0.2032 0.3048)
						)
						(arc
							(start -0.2032 0.3048)
							(mid -0.275042 0.275042)
							(end -0.3048 0.2032)
						)
						(arc
							(start -0.3048 -0.2032)
							(mid -0.275042 -0.275042)
							(end -0.2032 -0.3048)
						)
						(arc
							(start 0.2032 -0.3048)
							(mid 0.275042 -0.275042)
							(end 0.3048 -0.2032)
						)
					)
					(width 0)
					(fill yes)
				)
			)
		)
	)
	(footprint ""
		(layer "B.Cu")
		(at 44.52493 -77.650086)
		(property "Reference" "SC1276"
			(at 0 0 0)
			(layer "B.SilkS")
			(hide yes)
			(effects
				(font
					(size 1.27 1.27)
				)
				(justify mirror)
			)
		)
		(property "Value" "SCD01U50V2KX-1GP"
			(at -1.1811 -2.7051 0)
			(unlocked yes)
			(layer "B.Fab")
			(hide yes)
			(effects
				(font
					(size 1.016 1.016)
					(thickness 0.1524)
				)
				(justify mirror)
			)
		)
		(property "Device Type" "C402H22"
			(at -1.1811 -4.2291 0)
			(unlocked yes)
			(layer "B.Fab")
			(hide yes)
			(effects
				(font
					(size 1.016 1.016)
					(thickness 0.1524)
				)
				(justify mirror)
			)
		)
		(duplicate_pad_numbers_are_jumpers no)
		(fp_rect
			(start 0.4318 0.9525)
			(end -0.4318 -0.9525)
			(stroke
				(width 0)
				(type default)
			)
			(fill no)
			(layer "B.CrtYd")
		)
		(fp_rect
			(start 0.4318 0.9525)
			(end -0.4318 -0.9525)
			(stroke
				(width 0)
				(type default)
			)
			(fill no)
			(layer "B.Fab")
		)
		(pad "1" smd custom
			(at 0 -0.4445 180)
			(size 0.1524 0.1524)
			(layers "B.Cu" "B.Mask" "B.Paste")
			(net "SAS_EXP2CONN_RX_P_21")
			(options
				(clearance outline)
				(anchor circle)
			)
			(primitives
				(gr_poly
					(pts
						(arc
							(start 0.3048 0.2032)
							(mid 0.275042 0.275042)
							(end 0.2032 0.3048)
						)
						(arc
							(start -0.2032 0.3048)
							(mid -0.275042 0.275042)
							(end -0.3048 0.2032)
						)
						(arc
							(start -0.3048 -0.2032)
							(mid -0.275042 -0.275042)
							(end -0.2032 -0.3048)
						)
						(arc
							(start 0.2032 -0.3048)
							(mid 0.275042 -0.275042)
							(end 0.3048 -0.2032)
						)
					)
					(width 0)
					(fill yes)
				)
			)
		)
		(pad "2" smd custom
			(at 0 0.4445 180)
			(size 0.1524 0.1524)
			(layers "B.Cu" "B.Mask" "B.Paste")
			(net "MINI_RX_P_21")
			(options
				(clearance outline)
				(anchor circle)
			)
			(primitives
				(gr_poly
					(pts
						(arc
							(start 0.3048 0.2032)
							(mid 0.275042 0.275042)
							(end 0.2032 0.3048)
						)
						(arc
							(start -0.2032 0.3048)
							(mid -0.275042 0.275042)
							(end -0.3048 0.2032)
						)
						(arc
							(start -0.3048 -0.2032)
							(mid -0.275042 -0.275042)
							(end -0.2032 -0.3048)
						)
						(arc
							(start 0.2032 -0.3048)
							(mid 0.275042 -0.275042)
							(end 0.3048 -0.2032)
						)
					)
					(width 0)
					(fill yes)
				)
			)
		)
	)
	(footprint ""
		(layer "B.Cu")
		(at 288.925 -166.243 180)
		(property "Reference" "R253"
			(at 0 0 0)
			(layer "B.SilkS")
			(hide yes)
			(effects
				(font
					(size 1.27 1.27)
				)
				(justify mirror)
			)
		)
		(property "Value" "0R2J-2-GP"
			(at -0.064008 -3.993896 180)
			(unlocked yes)
			(layer "B.Fab")
			(hide yes)
			(effects
				(font
					(size 1.016 1.016)
					(thickness 0.1524)
				)
				(justify mirror)
			)
		)
		(property "Device Type" "R402H16"
			(at -0.064008 -5.517896 180)
			(unlocked yes)
			(layer "B.Fab")
			(hide yes)
			(effects
				(font
					(size 1.016 1.016)
					(thickness 0.1524)
				)
				(justify mirror)
			)
		)
		(duplicate_pad_numbers_are_jumpers no)
		(fp_line
			(start 0.508 -0.9398)
			(end 0.508 0.9398)
			(stroke
				(width 0.1524)
				(type default)
			)
			(layer "B.SilkS")
		)
		(fp_line
			(start -0.508 -0.9398)
			(end 0.508 -0.9398)
			(stroke
				(width 0.1524)
				(type default)
			)
			(layer "B.SilkS")
		)
		(fp_rect
			(start 0.508 0.9398)
			(end -0.508 -0.9398)
			(stroke
				(width 0)
				(type default)
			)
			(fill no)
			(layer "B.CrtYd")
		)
		(fp_rect
			(start 0.508 0.9398)
			(end -0.508 -0.9398)
			(stroke
				(width 0)
				(type default)
			)
			(fill no)
			(layer "B.Fab")
		)
		(pad "1" smd custom
			(at 0 -0.4445)
			(size 0.1397 0.1397)
			(layers "B.Cu" "B.Mask" "B.Paste")
			(net "PMU_PLTRST_N")
			(options
				(clearance outline)
				(anchor circle)
			)
			(primitives
				(gr_poly
					(pts
						(arc
							(start -0.1778 0.2794)
							(mid -0.249642 0.249642)
							(end -0.2794 0.1778)
						)
						(arc
							(start -0.2794 -0.1778)
							(mid -0.249642 -0.249642)
							(end -0.1778 -0.2794)
						)
						(arc
							(start 0.1778 -0.2794)
							(mid 0.249642 -0.249642)
							(end 0.2794 -0.1778)
						)
						(arc
							(start 0.2794 0.1778)
							(mid 0.249642 0.249642)
							(end 0.1778 0.2794)
						)
					)
					(width 0)
					(fill yes)
				)
			)
		)
		(pad "2" smd custom
			(at 0 0.4445)
			(size 0.1397 0.1397)
			(layers "B.Cu" "B.Mask" "B.Paste")
			(net "BMC0_PMU_PLTRST_N_BMC")
			(options
				(clearance outline)
				(anchor circle)
			)
			(primitives
				(gr_poly
					(pts
						(arc
							(start -0.1778 0.2794)
							(mid -0.249642 0.249642)
							(end -0.2794 0.1778)
						)
						(arc
							(start -0.2794 -0.1778)
							(mid -0.249642 -0.249642)
							(end -0.1778 -0.2794)
						)
						(arc
							(start 0.1778 -0.2794)
							(mid 0.249642 -0.249642)
							(end 0.2794 -0.1778)
						)
						(arc
							(start 0.2794 0.1778)
							(mid 0.249642 0.249642)
							(end 0.1778 0.2794)
						)
					)
					(width 0)
					(fill yes)
				)
			)
		)
	)
	(footprint ""
		(layer "B.Cu")
		(at 109.20476 -38.9382)
		(property "Reference" "SR665"
			(at 0 0 0)
			(layer "B.SilkS")
			(hide yes)
			(effects
				(font
					(size 1.27 1.27)
				)
				(justify mirror)
			)
		)
		(property "Value" "10KR2F-2-GP"
			(at -0.064008 -3.993896 0)
			(unlocked yes)
			(layer "B.Fab")
			(hide yes)
			(effects
				(font
					(size 1.016 1.016)
					(thickness 0.1524)
				)
				(justify mirror)
			)
		)
		(property "Device Type" "R402H16"
			(at -0.064008 -5.517896 0)
			(unlocked yes)
			(layer "B.Fab")
			(hide yes)
			(effects
				(font
					(size 1.016 1.016)
					(thickness 0.1524)
				)
				(justify mirror)
			)
		)
		(duplicate_pad_numbers_are_jumpers no)
		(fp_line
			(start -0.508 -0.9398)
			(end 0.508 -0.9398)
			(stroke
				(width 0.1524)
				(type default)
			)
			(layer "B.SilkS")
		)
		(fp_line
			(start 0.508 -0.9398)
			(end 0.508 0.9398)
			(stroke
				(width 0.1524)
				(type default)
			)
			(layer "B.SilkS")
		)
		(fp_rect
			(start 0.508 0.9398)
			(end -0.508 -0.9398)
			(stroke
				(width 0)
				(type default)
			)
			(fill no)
			(layer "B.CrtYd")
		)
		(fp_rect
			(start 0.508 0.9398)
			(end -0.508 -0.9398)
			(stroke
				(width 0)
				(type default)
			)
			(fill no)
			(layer "B.Fab")
		)
		(pad "1" smd custom
			(at 0 -0.4445 180)
			(size 0.1397 0.1397)
			(layers "B.Cu" "B.Mask" "B.Paste")
			(net "P1V8_C")
			(options
				(clearance outline)
				(anchor circle)
			)
			(primitives
				(gr_poly
					(pts
						(arc
							(start -0.1778 0.2794)
							(mid -0.249642 0.249642)
							(end -0.2794 0.1778)
						)
						(arc
							(start -0.2794 -0.1778)
							(mid -0.249642 -0.249642)
							(end -0.1778 -0.2794)
						)
						(arc
							(start 0.1778 -0.2794)
							(mid 0.249642 -0.249642)
							(end 0.2794 -0.1778)
						)
						(arc
							(start 0.2794 0.1778)
							(mid 0.249642 0.249642)
							(end 0.1778 0.2794)
						)
					)
					(width 0)
					(fill yes)
				)
			)
		)
		(pad "2" smd custom
			(at 0 0.4445 180)
			(size 0.1397 0.1397)
			(layers "B.Cu" "B.Mask" "B.Paste")
			(net "SYS_DBMODE0")
			(options
				(clearance outline)
				(anchor circle)
			)
			(primitives
				(gr_poly
					(pts
						(arc
							(start -0.1778 0.2794)
							(mid -0.249642 0.249642)
							(end -0.2794 0.1778)
						)
						(arc
							(start -0.2794 -0.1778)
							(mid -0.249642 -0.249642)
							(end -0.1778 -0.2794)
						)
						(arc
							(start 0.1778 -0.2794)
							(mid 0.249642 -0.249642)
							(end 0.2794 -0.1778)
						)
						(arc
							(start 0.2794 0.1778)
							(mid 0.249642 0.249642)
							(end 0.1778 0.2794)
						)
					)
					(width 0)
					(fill yes)
				)
			)
		)
	)
	(footprint ""
		(layer "B.Cu")
		(at 186.363864 -33.981136)
		(property "Reference" "C229"
			(at 0 0 0)
			(layer "B.SilkS")
			(hide yes)
			(effects
				(font
					(size 1.27 1.27)
				)
				(justify mirror)
			)
		)
		(property "Value" "SCD1U16V2KX-3GP"
			(at -1.1811 -2.7051 0)
			(unlocked yes)
			(layer "B.Fab")
			(hide yes)
			(effects
				(font
					(size 1.016 1.016)
					(thickness 0.1524)
				)
				(justify mirror)
			)
		)
		(property "Device Type" "C402H22"
			(at -1.1811 -4.2291 0)
			(unlocked yes)
			(layer "B.Fab")
			(hide yes)
			(effects
				(font
					(size 1.016 1.016)
					(thickness 0.1524)
				)
				(justify mirror)
			)
		)
		(duplicate_pad_numbers_are_jumpers no)
		(fp_rect
			(start 0.4318 0.9525)
			(end -0.4318 -0.9525)
			(stroke
				(width 0)
				(type default)
			)
			(fill no)
			(layer "B.CrtYd")
		)
		(fp_rect
			(start 0.4318 0.9525)
			(end -0.4318 -0.9525)
			(stroke
				(width 0)
				(type default)
			)
			(fill no)
			(layer "B.Fab")
		)
		(pad "1" smd custom
			(at 0 -0.4445 180)
			(size 0.1524 0.1524)
			(layers "B.Cu" "B.Mask" "B.Paste")
			(net "P3V3_STBY")
			(options
				(clearance outline)
				(anchor circle)
			)
			(primitives
				(gr_poly
					(pts
						(arc
							(start 0.3048 0.2032)
							(mid 0.275042 0.275042)
							(end 0.2032 0.3048)
						)
						(arc
							(start -0.2032 0.3048)
							(mid -0.275042 0.275042)
							(end -0.3048 0.2032)
						)
						(arc
							(start -0.3048 -0.2032)
							(mid -0.275042 -0.275042)
							(end -0.2032 -0.3048)
						)
						(arc
							(start 0.2032 -0.3048)
							(mid 0.275042 -0.275042)
							(end 0.3048 -0.2032)
						)
					)
					(width 0)
					(fill yes)
				)
			)
		)
		(pad "2" smd custom
			(at 0 0.4445 180)
			(size 0.1524 0.1524)
			(layers "B.Cu" "B.Mask" "B.Paste")
			(net "GND")
			(options
				(clearance outline)
				(anchor circle)
			)
			(primitives
				(gr_poly
					(pts
						(arc
							(start 0.3048 0.2032)
							(mid 0.275042 0.275042)
							(end 0.2032 0.3048)
						)
						(arc
							(start -0.2032 0.3048)
							(mid -0.275042 0.275042)
							(end -0.3048 0.2032)
						)
						(arc
							(start -0.3048 -0.2032)
							(mid -0.275042 -0.275042)
							(end -0.2032 -0.3048)
						)
						(arc
							(start 0.2032 -0.3048)
							(mid 0.275042 -0.275042)
							(end 0.3048 -0.2032)
						)
					)
					(width 0)
					(fill yes)
				)
			)
		)
	)
)
